FILE_TYPE = CONNECTIVITY;
{Allegro Design Entry HDL 16.6-p007 (v16-6-112F) 10/10/2012}
"PAGE_NUMBER" = 101;
0"NC";
1"P3V3_STBY_MNG\g";
2"P3V3_STBY_MNG_RGMII\g"VOLTAGE"+3.3V";
3"P3V3_STBY_MNG\g";
4"P3V3_STBY_MNG_RMII\g"VOLTAGE"+3.3V";
5"GND\g";
6"GND\g";
7"P3V3_STBY\g";
8"P3V3_STBY_MNG\g";
9"P3V3_STBY_MNG\g";
10"P3V3_STBY_MNG_RGMII\g";
11"P3V3_STBY_MNG_RMII\g";
12"P3V3_STBY_MNG_CPU\g";
13"P3V3_STBY_MNG\g"VOLTAGE"+3.3V";
14"P3V3_STBY_MNG_CPU\g"VOLTAGE"+3.3V";
15"GND\g";
16"GND\g";
17"GND\g";
18"GND\g";
19"GND\g";
20"GND\g";
21"GND\g";
22"CLK_50M_CKMNG_BMC_2_R";
23"CLK_50M_CKMNG_PCH_10GBE_R";
24"CLK_50M_CKMNG_SPRVLLE_R";
25"CLK_25M_BMC_R";
26"PD_CKMNG_OE";
27"XTAL_CK_MNG_IN";
28"XTAL_CK_MNG_OUT";
29"TP_33P_33M_SMBADR";
30"PWRGD_P3V3_STBY";
31"SMB_HOST_STBY_LVC3_SDA";
32"SMB_HOST_STBY_LVC3_SCL";
33"TP_CLK_125M";
34"TP_CLK_125M_BMCA";
35"TP_CLK_96M_CKMNG_N";
36"TP_CLK_96M_CKMNG_P";
37"TP_CLK_100M_R_DN";
38"TP_CLK_100M_R_DP";
39"A_COMP_CKMNG";
40"TP_CLK5_50M_CKMNG";
41"CLK_50M_CKMNG_BMC_1_R";
42"CLK_50M_CKMNG_OCP_R";
43"CLK_32K_SUSCLK_PLD_R";
44"CLK_25M_CPLD_R";
45"CLK_50M_CKMNG_BMC_1";
46"CLK_50M_CKMNG_OCP";
47"CLK_50M_CKMNG_BMC_2";
48"CLK_50M_CKMNG_SPRVLLE";
49"CLK_32K_SUSCLK_PLD";
50"CLK_25M_BMC";
51"CLK_50M_CKMNG_PCH_10GBE";
52"CLK_25M_CPLD";
%"VCC_CORE"
"1","(-3850,4350)","0","mstr_symbols","I100";
;
VOLTAGE"5"
CDS_LIB"mstr_symbols"
HDL_POWER"P3V3_STBY_MNG";
"A"1;
%"VCC_CORE"
"1","(-2975,4275)","0","mstr_symbols","I101";
;
VOLTAGE"3.3"
CDS_LIB"mstr_symbols"
HDL_POWER"P3V3_STBY_MNG_RGMII";
"A"2;
%"VCC_CORE"
"1","(-2425,4375)","0","mstr_symbols","I102";
;
VOLTAGE"5"
CDS_LIB"mstr_symbols"
HDL_POWER"P3V3_STBY_MNG";
"A"3;
%"VCC_CORE"
"1","(-1675,4325)","0","mstr_symbols","I103";
;
VOLTAGE"3.3"
CDS_LIB"mstr_symbols"
HDL_POWER"P3V3_STBY_MNG_RMII";
"A"4;
%"CAP_A"
"1","(-4875,4000)","0","dev_discrete","I104";
;
CDS_LOCATION"C2T18"
BOM_COST"SM_CONTROLLER"
CDS_LIB"dev_discrete"
CDS_SEC"1"
$SEC"1"
ROOM"SYS_CLOCK"
LOCATION"C2T18"
PART_NUMBER"A36096-045"
VALUE"0.01UF"
TOLERANCE"10%"
PACK_TYPE"0402V"
VOLTAGE"25V"
MATERIAL"X7R";
"B"
$PN"2"5;
"A"
$PN"1"12;
%"RES"
"1","(-5150,4175)","0","mstr_discrete","I105";
;
CDS_SEC"1"
SEC_TYPE"0603"
BOM_COST"SM_CONTROLLER"
CDS_LIB"mstr_discrete"
SEC"1"
CDS_LOCATION"R2T21"
ROOM"SYS_CLOCK"
LOCATION"R2T21"
PART_NUMBER"G22026-127"
VALUE"2.2"
TOLERANCE"1.0%"
PACK_TYPE"0603"
MATERIAL"CHIP"
WATTAGE"1/10W";
"B"
$PN"2"12;
"A"
$PN"1"9;
%"CAP_A"
"1","(-4475,4000)","0","dev_discrete","I106";
;
CDS_LOCATION"C2T19"
BOM_COST"SM_CONTROLLER"
CDS_LIB"dev_discrete"
CDS_SEC"1"
$SEC"1"
ROOM"SYS_CLOCK"
LOCATION"C2T19"
PART_NUMBER"D97712-004"
VALUE"1.0UF"
TOLERANCE"10%"
PACK_TYPE"0402V"
VOLTAGE"6.3V"
MATERIAL"X6S";
"B"
$PN"2"5;
"A"
$PN"1"12;
%"GND"
"1","(-4475,3675)","0","mstr_symbols","I107";
;
VOLTAGE"0.0V"
SIZE"1B"
CDS_LIB"mstr_symbols"
BOM_COST"SM_CONTROLLER"
BODY_TYPE"PLUMBING"
ROOM"SYS_CLOCK"
HDL_POWER"GND";
"A\NAC"5;
%"GND"
"1","(-6600,3625)","0","mstr_symbols","I108";
;
VOLTAGE"0.0V"
BOM_COST"SM_CONTROLLER"
CDS_LIB"mstr_symbols"
SIZE"1B"
BODY_TYPE"PLUMBING"
ROOM"SYS_CLOCK"
HDL_POWER"GND";
"A\NAC"6;
%"CAP_A"
"1","(-6600,3975)","0","dev_discrete","I109";
;
ROOM"SYS_CLOCK"
CDS_LOCATION"C2T34"
BOM_COST"SM_CONTROLLER"
CDS_LIB"dev_discrete"
CDS_SEC"1"
SEC_TYPE"0402V"
SEC"1"
LOCATION"C2T34"
PART_NUMBER"A36096-030"
VALUE"0.1UF"
TOLERANCE"10%"
PACK_TYPE"0402V"
VOLTAGE"16V"
MATERIAL"X7R";
"B"
$PN"2"6;
"A"
$PN"1"8;
%"CAP_A"
"1","(-6900,3975)","0","dev_discrete","I110";
;
ROOM"SYS_CLOCK"
CDS_LOCATION"C2T30"
BOM_COST"SM_CONTROLLER"
CDS_LIB"dev_discrete"
CDS_SEC"1"
$SEC"1"
LOCATION"C2T30"
PART_NUMBER"A36096-030"
VALUE"0.1UF"
TOLERANCE"10%"
PACK_TYPE"0402V"
VOLTAGE"16V"
MATERIAL"X7R";
"B"
$PN"2"6;
"A"
$PN"1"8;
%"CAP_A"
"1","(-7300,3975)","0","dev_discrete","I111";
;
ROOM"SYS_CLOCK"
CDS_LOCATION"C2T25"
BOM_COST"SM_CONTROLLER"
CDS_LIB"dev_discrete"
CDS_SEC"1"
$SEC"1"
LOCATION"C2T25"
PART_NUMBER"A36096-030"
VALUE"0.1UF"
TOLERANCE"10%"
PACK_TYPE"0402V"
VOLTAGE"16V"
MATERIAL"X7R";
"B"
$PN"2"6;
"A"
$PN"1"8;
%"CAP_A"
"1","(-7600,3975)","0","dev_discrete","I112";
;
ROOM"SYS_CLOCK"
CDS_LOCATION"C2T17"
BOM_COST"SM_CONTROLLER"
CDS_LIB"dev_discrete"
CDS_SEC"1"
$SEC"1"
LOCATION"C2T17"
PART_NUMBER"A36096-030"
VALUE"0.1UF"
TOLERANCE"10%"
PACK_TYPE"0402V"
VOLTAGE"16V"
MATERIAL"X7R";
"B"
$PN"2"6;
"A"
$PN"1"8;
%"CAP"
"1","(-7900,3975)","0","mstr_discrete","I113";
;
CDS_SEC"1"
CDS_LIB"mstr_discrete"
BOM_COST"SM_CONTROLLER"
SEC_TYPE"0805"
SEC"1"
CDS_LOCATION"C2T22"
ROOM"SYS_CLOCK"
LOCATION"C2T22"
PART_NUMBER"C95333-007"
VALUE"10UF"
TOLERANCE"10%"
PACK_TYPE"0805"
VOLTAGE"16V"
MATERIAL"X6S";
"A"
$PN"1"8;
"B"
$PN"2"6;
%"FERRITE"
"1","(-8125,4125)","0","mstr_discrete","I114";
;
BOM_COST"SM_CONTROLLER"
CDS_LIB"mstr_discrete"
CDS_SEC"1"
$SEC"1"
CDS_LOCATION"FB2T2"
ROOM"SYS_CLOCK"
LOCATION"FB2T2"
PART_NUMBER"656554-043"
VALUE"600"
PACK_TYPE"SMLF"
MATERIAL"FB";
"A"
$PN"1"7;
"B"
$PN"2"8;
%"P3V3_STBY"
"1","(-8475,4350)","0","mstr_symbols","I115";
;
VOLTAGE"3.3"
SIZE"1B"
CDS_LIB"mstr_symbols"
BODY_TYPE"PLUMBING"
HDL_POWER"P3V3_STBY";
"G\NAC"7;
%"CAP_A"
"1","(-8475,3950)","0","dev_discrete","I116";
;
CDS_LOCATION"C2T28"
BOM_COST"SM_CONTROLLER"
CDS_LIB"dev_discrete"
CDS_SEC"1"
$SEC"1"
ROOM"SYS_CLOCK"
LOCATION"C2T28"
PART_NUMBER"D97712-004"
VALUE"1.0UF"
TOLERANCE"10%"
PACK_TYPE"0402V"
VOLTAGE"6.3V"
MATERIAL"X6S";
"B"
$PN"2"18;
"A"
$PN"1"7;
%"VCC_CORE"
"1","(-6600,4275)","0","mstr_symbols","I117";
;
VOLTAGE"5"
CDS_LIB"mstr_symbols"
HDL_POWER"P3V3_STBY_MNG";
"A"8;
%"VCC_CORE"
"1","(-5425,4375)","0","mstr_symbols","I118";
;
VOLTAGE"5"
CDS_LIB"mstr_symbols"
HDL_POWER"P3V3_STBY_MNG";
"A"9;
%"VCC_CORE"
"1","(-6675,3200)","0","mstr_symbols","I119";
;
VOLTAGE"3.3"
CDS_LIB"mstr_symbols"
HDL_POWER"P3V3_STBY_MNG_RGMII";
"A"10;
%"VCC_CORE"
"1","(-6975,3000)","0","mstr_symbols","I120";
;
VOLTAGE"3.3"
CDS_LIB"mstr_symbols"
HDL_POWER"P3V3_STBY_MNG_RMII";
"A"11;
%"VCC_CORE"
"1","(-4475,4325)","0","mstr_symbols","I121";
;
VOLTAGE"3.3"
CDS_LIB"mstr_symbols"
HDL_POWER"P3V3_STBY_MNG_CPU";
"A"12;
%"VCC_CORE"
"1","(-7375,2500)","0","mstr_symbols","I122";
;
VOLTAGE"5"
CDS_LIB"mstr_symbols"
HDL_POWER"P3V3_STBY_MNG";
"A"13;
%"VCC_CORE"
"1","(-7875,2375)","0","mstr_symbols","I123";
;
VOLTAGE"3.3"
CDS_LIB"mstr_symbols"
HDL_POWER"P3V3_STBY_MNG_CPU";
"A"14;
%"RES"
"1","(-3425,1525)","0","mstr_discrete","I124";
;
CDS_SEC"1"
BOM_COST"SM_CONTROLLER"
CDS_LIB"mstr_discrete"
SEC_TYPE"0402"
SEC"1"
CDS_LOCATION"R2T42"
ROOM"SYS_CLOCK"
LOCATION"R2T42"
PART_NUMBER"G21796-250"
VALUE"22.1"
TOLERANCE"1.0%"
PACK_TYPE"0402"
MATERIAL"CHIP"
WATTAGE"1/16W";
"B"
$PN"2"46;
"A"
$PN"1"42;
%"RES"
"1","(-3425,1675)","0","mstr_discrete","I125";
;
CDS_SEC"1"
SEC_TYPE"0402"
CDS_LIB"mstr_discrete"
BOM_COST"SM_CONTROLLER"
SEC"1"
CDS_LOCATION"R2T46"
ROOM"SYS_CLOCK"
LOCATION"R2T46"
PART_NUMBER"G21796-250"
VALUE"22.1"
TOLERANCE"1.0%"
PACK_TYPE"0402"
MATERIAL"CHIP"
WATTAGE"1/16W";
"B"
$PN"2"45;
"A"
$PN"1"41;
%"RES"
"1","(-3425,2750)","0","mstr_discrete","I129";
;
BOM_COST"SM_CONTROLLER"
CDS_LIB"mstr_discrete"
CDS_SEC"1"
$SEC"1"
CDS_LOCATION"R8F27"
ROOM"SYS_CLOCK"
LOCATION"R8F27"
PART_NUMBER"G21796-250"
VALUE"22.1"
TOLERANCE"1.0%"
PACK_TYPE"0402"
MATERIAL"CHIP"
WATTAGE"1/16W";
"B"
$PN"2"49;
"A"
$PN"1"43;
%"RES"
"1","(-3425,2575)","0","mstr_discrete","I130";
;
CDS_SEC"1"
SEC_TYPE"0402"
CDS_LIB"mstr_discrete"
BOM_COST"SM_CONTROLLER"
SEC"1"
CDS_LOCATION"R2T47"
ROOM"SYS_CLOCK"
LOCATION"R2T47"
PART_NUMBER"G21796-074"
VALUE"33.2"
TOLERANCE"1%"
PACK_TYPE"0402"
MATERIAL"CHIP"
WATTAGE"1/16W";
"B"
$PN"2"52;
"A"
$PN"1"44;
%"RES"
"1","(-3425,1975)","0","mstr_discrete","I131";
;
CDS_SEC"1"
CDS_LOCATION"R8G25"
CDS_LIB"mstr_discrete"
SEC_TYPE"0402"
SEC"1"
LOCATION"R8G25"
PART_NUMBER"G21796-074"
VALUE"33.2"
TOLERANCE"1%"
PACK_TYPE"0402"
MATERIAL"CHIP"
WATTAGE"1/16W";
"B"
$PN"2"48;
"A"
$PN"1"24;
%"RES"
"1","(-3425,2125)","0","mstr_discrete","I132";
;
CDS_SEC"1"
CDS_LOCATION"R8G24"
CDS_LIB"mstr_discrete"
SEC_TYPE"0402"
SEC"1"
ROOM"SB"
LOCATION"R8G24"
PART_NUMBER"G21796-074"
VALUE"33.2"
TOLERANCE"1%"
PACK_TYPE"0402"
MATERIAL"CHIP"
WATTAGE"1/16W";
"B"
$PN"2"51;
"A"
$PN"1"23;
%"RES"
"1","(-3425,1825)","0","mstr_discrete","I133";
;
CDS_LIB"mstr_discrete"
CDS_SEC"1"
$SEC"1"
CDS_LOCATION"R8G1"
LOCATION"R8G1"
PART_NUMBER"G21796-074"
VALUE"33.2"
TOLERANCE"1%"
PACK_TYPE"0402"
MATERIAL"CHIP"
WATTAGE"1/16W";
"B"
$PN"2"47;
"A"
$PN"1"22;
%"RES"
"1","(-3425,2425)","0","mstr_discrete","I20";
;
CDS_SEC"1"
BOM_COST"SM_CONTROLLER"
SEC_TYPE"0402"
CDS_LIB"mstr_discrete"
SEC"1"
CDS_LOCATION"R8F29"
ROOM"SYS_CLOCK"
LOCATION"R8F29"
PART_NUMBER"G21796-074"
VALUE"33.2"
TOLERANCE"1%"
PACK_TYPE"0402"
MATERIAL"CHIP"
WATTAGE"1/16W";
"B"
$PN"2"50;
"A"
$PN"1"25;
%"RES"
"2","(-4750,2975)","2","mstr_discrete","I28";
;
CDS_LIB"mstr_discrete"
BOM_COST"SM_CONTROLLER"
CDS_SEC"1"
$SEC"1"
CDS_LOCATION"R8F25"
ROOM"SYS_CLOCK"
LOCATION"R8F25"
PART_NUMBER"G21796-077"
VALUE"475.0"
TOLERANCE"1%"
PACK_TYPE"0402"
MATERIAL"CHIP"
WATTAGE"1/16W";
"A"
$PN"1"39;
"B"
$PN"2"15;
%"GND"
"1","(-4750,2775)","0","mstr_symbols","I29";
;
VOLTAGE"0.0V"
CDS_LIB"mstr_symbols"
SIZE"1B"
BOM_COST"SM_CONTROLLER"
BODY_TYPE"PLUMBING"
ROOM"SYS_CLOCK"
HDL_POWER"GND";
"A\NAC"15;
%"GND"
"1","(-5025,775)","0","mstr_symbols","I33";
;
VOLTAGE"0.0V"
BOM_COST"SM_CONTROLLER"
CDS_LIB"mstr_symbols"
SIZE"1B"
BODY_TYPE"PLUMBING"
ROOM"SYS_CLOCK"
HDL_POWER"GND";
"A\NAC"16;
%"ICS9FGP204"
"1","(-5875,1825)","0","mstr_clock","I34";
;
CDS_SEC"1"
PACK_TYPE"MLFP"
BOM_COST"SM_CONTROLLER"
CDS_LIB"mstr_clock"
CDS_LMAN_SYM_OUTLINE"-600,900,600,-900"
SEC_TYPE"MLFP"
SEC"1"
CDS_LOCATION"EU8F2"
ROOM"SYS_CLOCK"
LOCATION"EU8F2"
PART_NUMBER"E95226-001"
MATERIAL"IC";
"RGMII<1>"
$PN"36"33;
"RGMII<0>"
$PN"37"34;
"GND_RGMII"
$PN"35"16;
"VDD_RGMII"
$PN"34"10;
"SMBDAT"
$PN"39"31;
"X2_25"
$PN"20"28;
"SMBCLK"
$PN"38"32;
"VTTPWR_GD_PD_N"
$PN"40"30;
"VDDCPU"
$PN"9"14;
"GNDCPU"
$PN"10"16;
"OE_CPU"
$PN"6"26;
"VDD96"
$PN"2"13;
"OE_96"
$PN"5"26;
"VDD33"
$PN"23"13;
"33MHZ_SMBADR"
$PN"22"29;
"GNDRMII<1>"
$PN"30"16;
"VDDRMII<1>"
$PN"31"11;
"VDDRMII<0>"
$PN"26"11;
"GNDRMII<0>"
$PN"27"16;
"X1_25"
$PN"19"27;
"IREF"
$PN"11"39;
"VDDREF"
$PN"15"13;
"CPUCLKT0"
$PN"7"38;
"GNDREF"
$PN"18"16;
"CPUCLKC0"
$PN"8"37;
"DOT96SST"
$PN"3"36;
"DOT96SSC"
$PN"4"35;
"GND<0>"
$PN"1"16;
"GND33"
$PN"21"16;
"GND<1>"
$PN"41"16;
"RMII<0>"
$PN"33"42;
"RMII<3>"
$PN"28"24;
"RMII<4>"
$PN"25"23;
"RMII<5>"
$PN"24"40;
"RMII<2>"
$PN"29"22;
"RMII<1>"
$PN"32"41;
"25MHZ_1"
$PN"17"44;
"25MHZ_0"
$PN"16"25;
"GND32K"
$PN"14"16;
"32KHZ"
$PN"13"43;
"VDD32K"
$PN"12"13;
%"RES"
"2","(-8300,1200)","0","mstr_discrete","I48";
;
CDS_SEC"1"
CDS_LIB"mstr_discrete"
BOM_COST"SM_CONTROLLER"
SEC_TYPE"0402"
SEC"1"
CDS_LOCATION"R2T25"
ROOM"SYS_CLOCK"
LOCATION"R2T25"
PART_NUMBER"G21796-026"
VALUE"1.00K"
TOLERANCE"1%"
PACK_TYPE"0402"
MATERIAL"CHIP"
WATTAGE"1/16W";
"A"
$PN"1"26;
"B"
$PN"2"19;
%"CAP"
"1","(-7275,775)","0","mstr_discrete","I49";
;
CDS_LIB"mstr_discrete"
BOM_COST"SM_CONTROLLER"
CDS_SEC"1"
$SEC"1"
CDS_LOCATION"C8F18"
ROOM"SYS_CLOCK"
LOCATION"C8F18"
PART_NUMBER"A36095-038"
VALUE"27.0PF"
TOLERANCE"5%"
PACK_TYPE"0402LF"
VOLTAGE"50V"
MATERIAL"COG";
"A"
$PN"1"27;
"B"
$PN"2"17;
%"CRYSTAL"
"3","(-7450,1000)","2","mstr_discrete","I52";
;
PACK_TYPE"2013LF"
BOM_COST"SM_CONTROLLER"
CDS_LIB"mstr_discrete"
CDS_SEC"1"
$SEC"1"
CDS_LOCATION"Y8F1"
ROOM"SYS_CLOCK"
POWER_GROUP"GND=GND"
LOCATION"Y8F1"
PART_NUMBER"D71700-033"
VALUE"25.000MHZ"
MATERIAL"IC";
"A"
$PN"1"27;
"B"
$PN"3"28;
%"CAP"
"1","(-7625,775)","2","mstr_discrete","I53";
;
CDS_LIB"mstr_discrete"
BOM_COST"SM_CONTROLLER"
CDS_SEC"1"
$SEC"1"
CDS_LOCATION"C8F19"
ROOM"SYS_CLOCK"
LOCATION"C8F19"
PART_NUMBER"A36095-038"
VALUE"27.0PF"
TOLERANCE"5%"
PACK_TYPE"0402LF"
VOLTAGE"50V"
MATERIAL"COG";
"A"
$PN"1"28;
"B"
$PN"2"17;
%"GND"
"1","(-7450,475)","0","mstr_symbols","I54";
;
VOLTAGE"0.0V"
CDS_LIB"mstr_symbols"
SIZE"1B"
BOM_COST"SM_CONTROLLER"
BODY_TYPE"PLUMBING"
ROOM"SYS_CLOCK"
HDL_POWER"GND";
"A\NAC"17;
%"GND"
"1","(-8475,3650)","0","mstr_symbols","I58";
;
VOLTAGE"0.0V"
BOM_COST"SM_CONTROLLER"
CDS_LIB"mstr_symbols"
SIZE"1B"
BODY_TYPE"PLUMBING"
ROOM"SYS_CLOCK"
HDL_POWER"GND";
"A\NAC"18;
%"GND"
"1","(-8300,875)","0","mstr_symbols","I64";
;
VOLTAGE"0.0V"
CDS_LIB"mstr_symbols"
SIZE"1B"
BOM_COST"SM_CONTROLLER"
BODY_TYPE"PLUMBING"
ROOM"SYS_CLOCK"
HDL_POWER"GND";
"A\NAC"19;
%"CAP_A"
"1","(-2975,3925)","0","dev_discrete","I89";
;
CDS_LOCATION"C2T31"
BOM_COST"SM_CONTROLLER"
CDS_LIB"dev_discrete"
CDS_SEC"1"
$SEC"1"
ROOM"SYS_CLOCK"
LOCATION"C2T31"
PART_NUMBER"D97712-004"
VALUE"1.0UF"
TOLERANCE"10%"
PACK_TYPE"0402V"
VOLTAGE"6.3V"
MATERIAL"X6S";
"B"
$PN"2"20;
"A"
$PN"1"2;
%"CAP_A"
"1","(-3400,3925)","0","dev_discrete","I90";
;
CDS_LOCATION"C2T27"
BOM_COST"SM_CONTROLLER"
CDS_LIB"dev_discrete"
CDS_SEC"1"
$SEC"1"
ROOM"SYS_CLOCK"
LOCATION"C2T27"
PART_NUMBER"A36096-045"
VALUE"0.01UF"
TOLERANCE"10%"
PACK_TYPE"0402V"
VOLTAGE"25V"
MATERIAL"X7R";
"B"
$PN"2"20;
"A"
$PN"1"2;
%"RES"
"1","(-3675,4150)","0","mstr_discrete","I94";
;
CDS_LIB"mstr_discrete"
BOM_COST"SM_CONTROLLER"
CDS_SEC"1"
$SEC"1"
CDS_LOCATION"R2T23"
ROOM"SYS_CLOCK"
LOCATION"R2T23"
PART_NUMBER"G22026-127"
VALUE"2.2"
TOLERANCE"1.0%"
PACK_TYPE"0603"
MATERIAL"CHIP"
WATTAGE"1/10W";
"B"
$PN"2"2;
"A"
$PN"1"1;
%"RES"
"1","(-2250,4200)","0","mstr_discrete","I95";
;
BOM_COST"SM_CONTROLLER"
CDS_LIB"mstr_discrete"
CDS_SEC"1"
$SEC"1"
CDS_LOCATION"R2T52"
ROOM"SYS_CLOCK"
LOCATION"R2T52"
PART_NUMBER"G22026-127"
VALUE"2.2"
TOLERANCE"1.0%"
PACK_TYPE"0603"
MATERIAL"CHIP"
WATTAGE"1/10W";
"B"
$PN"2"4;
"A"
$PN"1"3;
%"GND"
"1","(-2975,3625)","0","mstr_symbols","I96";
;
VOLTAGE"0.0V"
SIZE"1B"
CDS_LIB"mstr_symbols"
BOM_COST"SM_CONTROLLER"
BODY_TYPE"PLUMBING"
ROOM"SYS_CLOCK"
HDL_POWER"GND";
"A\NAC"20;
%"CAP_A"
"1","(-1675,4000)","0","dev_discrete","I97";
;
CDS_LOCATION"C2T38"
BOM_COST"SM_CONTROLLER"
CDS_LIB"dev_discrete"
CDS_SEC"1"
$SEC"1"
ROOM"SYS_CLOCK"
LOCATION"C2T38"
PART_NUMBER"D97712-004"
VALUE"1.0UF"
TOLERANCE"10%"
PACK_TYPE"0402V"
VOLTAGE"6.3V"
MATERIAL"X6S";
"B"
$PN"2"21;
"A"
$PN"1"4;
%"GND"
"1","(-1675,3650)","0","mstr_symbols","I98";
;
VOLTAGE"0.0V"
CDS_LIB"mstr_symbols"
SIZE"1B"
BOM_COST"SM_CONTROLLER"
BODY_TYPE"PLUMBING"
ROOM"SYS_CLOCK"
HDL_POWER"GND";
"A\NAC"21;
%"CAP_A"
"1","(-2050,4000)","0","dev_discrete","I99";
;
CDS_LOCATION"C2T37"
BOM_COST"SM_CONTROLLER"
CDS_LIB"dev_discrete"
CDS_SEC"1"
$SEC"1"
ROOM"SYS_CLOCK"
LOCATION"C2T37"
PART_NUMBER"A36096-045"
VALUE"0.01UF"
TOLERANCE"10%"
PACK_TYPE"0402V"
VOLTAGE"25V"
MATERIAL"X7R";
"B"
$PN"2"21;
"A"
$PN"1"4;
END.
